# S9S_MB_2U (Grand Teton) — schematic netlist excerpt (pin names and nets, part order shuffled) for the footprints in the layout excerpt that follows; sources: Cadence DE-HDL packaged netlist, KiCad conversion of 03242023_DA0F0TMBIJ0_F0T_Motherboard_J_brd_V01_OCP.brd

R4745  Q_RES  10K 1% CHIP  pkg 0402LF  page 158 : A = P3V3_AUX ; B = OCP_SFF_AUX_PWR_PLD_EN_R
R3083  Q_RES  130 1% CHIP  pkg 0402LF  page 256 : A = LED_RST_PLD_CPU1_DRAM_EF_N ; B = P3V3_AUX

(kicad_pcb
	(version 20260206)
	(generator "pcbnew")
	(generator_version "10.0")
	(general
		(thickness 1.6)
		(legacy_teardrops no)
	)
	(paper "A4")
	(title_block
		(title "03242023_DA0F0TMBIJ0_F0T_Motherboard_J_brd_V01_OCP.brd")
		(comment 1 "Grand Teton / footprints 3119-3120 of 6105")
	)
	(layers
		(0 "F.Cu" signal "TOP")
		(4 "In1.Cu" signal "GND")
		(6 "In2.Cu" signal "IN1")
		(8 "In3.Cu" signal "GND1")
		(10 "In4.Cu" signal "IN2")
		(12 "In5.Cu" signal "GND2")
		(14 "In6.Cu" signal "IN3")
		(16 "In7.Cu" signal "GND3")
		(18 "In8.Cu" signal "VCC")
		(20 "In9.Cu" signal "VCC1")
		(22 "In10.Cu" signal "GND4")
		(24 "In11.Cu" signal "IN4")
		(26 "In12.Cu" signal "GND5")
		(28 "In13.Cu" signal "IN5")
		(30 "In14.Cu" signal "GND6")
		(32 "In15.Cu" signal "IN6")
		(34 "In16.Cu" signal "GND7")
		(2 "B.Cu" signal "BOTTOM")
		(9 "F.Adhes" user "F.Adhesive")
		(11 "B.Adhes" user "B.Adhesive")
		(13 "F.Paste" user "Package Geometry/Pastemask Top")
		(15 "B.Paste" user "Package Geometry/Pastemask Bottom")
		(5 "F.SilkS" user "Ref Des/Silkscreen Top")
		(7 "B.SilkS" user "Ref Des/Silkscreen Bottom")
		(1 "F.Mask" user "Board Geometry/Soldermask Top")
		(3 "B.Mask" user "Board Geometry/Soldermask Bottom")
		(17 "Dwgs.User" user "User.Drawings")
		(19 "Cmts.User" user "User.Comments")
		(21 "Eco1.User" user "User.Eco1")
		(23 "Eco2.User" user "User.Eco2")
		(25 "Edge.Cuts" user "Board Geometry/Outline")
		(27 "Margin" user)
		(31 "F.CrtYd" user "Package Geometry/Place Bound Top")
		(29 "B.CrtYd" user "Package Geometry/Place Bound Bottom")
		(35 "F.Fab" user "Ref Des/Assembly Top")
		(33 "B.Fab" user "Ref Des/Assembly Bottom")
	)
	(footprint ""
		(layer "F.Cu")
		(at 440.38012 -100.27158 90)
		(property "Reference" "R4745"
			(at 0 0 90)
			(layer "F.SilkS")
			(hide yes)
			(effects
				(font
					(size 1.27 1.27)
				)
			)
		)
		(property "Value" ""
			(at 0 0 90)
			(layer "F.Fab")
			(effects
				(font
					(size 1.27 1.27)
				)
			)
		)
		(duplicate_pad_numbers_are_jumpers no)
		(fp_line
			(start 0.7874 -0.4064)
			(end 0.7874 0.4064)
			(stroke
				(width 0.1524)
				(type default)
			)
			(layer "F.SilkS")
		)
		(fp_line
			(start -0.7874 -0.4064)
			(end 0.7874 -0.4064)
			(stroke
				(width 0.1524)
				(type default)
			)
			(layer "F.SilkS")
		)
		(fp_line
			(start 0.7874 0.4064)
			(end -0.7874 0.4064)
			(stroke
				(width 0.1524)
				(type default)
			)
			(layer "F.SilkS")
		)
		(fp_line
			(start -0.7874 0.4064)
			(end -0.7874 -0.4064)
			(stroke
				(width 0.1524)
				(type default)
			)
			(layer "F.SilkS")
		)
		(fp_line
			(start -0.12065 -0.305054)
			(end -0.12065 -0.2794)
			(stroke
				(width 0.1)
				(type default)
			)
			(layer "F.Fab")
		)
		(fp_line
			(start -0.67945 -0.305054)
			(end -0.12065 -0.305054)
			(stroke
				(width 0.1)
				(type default)
			)
			(layer "F.Fab")
		)
		(fp_line
			(start 0.67945 -0.3048)
			(end 0.67945 0.3048)
			(stroke
				(width 0.1)
				(type default)
			)
			(layer "F.Fab")
		)
		(fp_line
			(start 0.12065 -0.3048)
			(end 0.67945 -0.3048)
			(stroke
				(width 0.1)
				(type default)
			)
			(layer "F.Fab")
		)
		(fp_line
			(start 0.12065 -0.2794)
			(end 0.12065 -0.3048)
			(stroke
				(width 0.1)
				(type default)
			)
			(layer "F.Fab")
		)
		(fp_line
			(start -0.12065 -0.2794)
			(end 0.12065 -0.2794)
			(stroke
				(width 0.1)
				(type default)
			)
			(layer "F.Fab")
		)
		(fp_line
			(start 0.120396 0.2794)
			(end -0.12065 0.2794)
			(stroke
				(width 0.1)
				(type default)
			)
			(layer "F.Fab")
		)
		(fp_line
			(start -0.12065 0.2794)
			(end -0.12065 0.3048)
			(stroke
				(width 0.1)
				(type default)
			)
			(layer "F.Fab")
		)
		(fp_line
			(start 0.67945 0.3048)
			(end 0.120396 0.3048)
			(stroke
				(width 0.1)
				(type default)
			)
			(layer "F.Fab")
		)
		(fp_line
			(start 0.120396 0.3048)
			(end 0.120396 0.2794)
			(stroke
				(width 0.1)
				(type default)
			)
			(layer "F.Fab")
		)
		(fp_line
			(start -0.12065 0.3048)
			(end -0.67945 0.3048)
			(stroke
				(width 0.1)
				(type default)
			)
			(layer "F.Fab")
		)
		(fp_line
			(start -0.67945 0.3048)
			(end -0.67945 -0.305054)
			(stroke
				(width 0.1)
				(type default)
			)
			(layer "F.Fab")
		)
		(pad "1" smd circle
			(at -0.40005 0 90)
			(size 0 0)
			(layers "F.Cu" "F.Mask" "F.Paste")
			(net "P3V3_AUX")
		)
		(pad "2" smd circle
			(at 0.40005 0 90)
			(size 0 0)
			(layers "F.Cu" "F.Mask" "F.Paste")
			(net "OCP_SFF_AUX_PWR_PLD_EN_R")
		)
	)
	(footprint ""
		(layer "F.Cu")
		(at 69.042534 -65.082674 -90)
		(property "Reference" "R3083"
			(at 0 0 270)
			(layer "F.SilkS")
			(hide yes)
			(effects
				(font
					(size 1.27 1.27)
				)
			)
		)
		(property "Value" ""
			(at 0 0 270)
			(layer "F.Fab")
			(effects
				(font
					(size 1.27 1.27)
				)
			)
		)
		(duplicate_pad_numbers_are_jumpers no)
		(fp_line
			(start -0.7874 0.4064)
			(end -0.7874 -0.4064)
			(stroke
				(width 0.1524)
				(type default)
			)
			(layer "F.SilkS")
		)
		(fp_line
			(start 0.7874 0.4064)
			(end -0.7874 0.4064)
			(stroke
				(width 0.1524)
				(type default)
			)
			(layer "F.SilkS")
		)
		(fp_line
			(start -0.7874 -0.4064)
			(end 0.7874 -0.4064)
			(stroke
				(width 0.1524)
				(type default)
			)
			(layer "F.SilkS")
		)
		(fp_line
			(start 0.7874 -0.4064)
			(end 0.7874 0.4064)
			(stroke
				(width 0.1524)
				(type default)
			)
			(layer "F.SilkS")
		)
		(fp_line
			(start -0.67945 0.3048)
			(end -0.67945 -0.305054)
			(stroke
				(width 0.1)
				(type default)
			)
			(layer "F.Fab")
		)
		(fp_line
			(start -0.12065 0.3048)
			(end -0.67945 0.3048)
			(stroke
				(width 0.1)
				(type default)
			)
			(layer "F.Fab")
		)
		(fp_line
			(start 0.120396 0.3048)
			(end 0.120396 0.2794)
			(stroke
				(width 0.1)
				(type default)
			)
			(layer "F.Fab")
		)
		(fp_line
			(start 0.67945 0.3048)
			(end 0.120396 0.3048)
			(stroke
				(width 0.1)
				(type default)
			)
			(layer "F.Fab")
		)
		(fp_line
			(start -0.12065 0.2794)
			(end -0.12065 0.3048)
			(stroke
				(width 0.1)
				(type default)
			)
			(layer "F.Fab")
		)
		(fp_line
			(start 0.120396 0.2794)
			(end -0.12065 0.2794)
			(stroke
				(width 0.1)
				(type default)
			)
			(layer "F.Fab")
		)
		(fp_line
			(start -0.12065 -0.2794)
			(end 0.12065 -0.2794)
			(stroke
				(width 0.1)
				(type default)
			)
			(layer "F.Fab")
		)
		(fp_line
			(start 0.12065 -0.2794)
			(end 0.12065 -0.3048)
			(stroke
				(width 0.1)
				(type default)
			)
			(layer "F.Fab")
		)
		(fp_line
			(start 0.12065 -0.3048)
			(end 0.67945 -0.3048)
			(stroke
				(width 0.1)
				(type default)
			)
			(layer "F.Fab")
		)
		(fp_line
			(start 0.67945 -0.3048)
			(end 0.67945 0.3048)
			(stroke
				(width 0.1)
				(type default)
			)
			(layer "F.Fab")
		)
		(fp_line
			(start -0.67945 -0.305054)
			(end -0.12065 -0.305054)
			(stroke
				(width 0.1)
				(type default)
			)
			(layer "F.Fab")
		)
		(fp_line
			(start -0.12065 -0.305054)
			(end -0.12065 -0.2794)
			(stroke
				(width 0.1)
				(type default)
			)
			(layer "F.Fab")
		)
		(pad "1" smd circle
			(at -0.40005 0 270)
			(size 0 0)
			(layers "F.Cu" "F.Mask" "F.Paste")
			(net "LED_RST_PLD_CPU1_DRAM_EF_N")
		)
		(pad "2" smd circle
			(at 0.40005 0 270)
			(size 0 0)
			(layers "F.Cu" "F.Mask" "F.Paste")
			(net "P3V3_AUX")
		)
	)
)
